(kicad_pcb
	(version 20260206)
	(generator "pcbnew")
	(generator_version "10.0")
	(general
		(thickness 1.6)
		(legacy_teardrops no)
	)
	(paper "A4")
	(title_block
		(title "baseboard — 13948-1b.1110WZS1818.brd")
		(comment 1 "Honey Badger (Wiwynn) / footprints 1676-1682 of 2523")
	)
	(layers
		(0 "F.Cu" signal "TOP")
		(4 "In1.Cu" signal "L2GND")
		(6 "In2.Cu" signal "L3")
		(8 "In3.Cu" signal "L4VCC")
		(10 "In4.Cu" signal "L5VCC")
		(12 "In5.Cu" signal "L6")
		(14 "In6.Cu" signal "L7GND")
		(2 "B.Cu" signal "BOTTOM")
		(9 "F.Adhes" user "F.Adhesive")
		(11 "B.Adhes" user "B.Adhesive")
		(13 "F.Paste" user "Package Geometry/Pastemask Top")
		(15 "B.Paste" user "Package Geometry/Pastemask Bottom")
		(5 "F.SilkS" user "Ref Des/Silkscreen Top")
		(7 "B.SilkS" user "Ref Des/Silkscreen Bottom")
		(1 "F.Mask" user "Board Geometry/Soldermask Top")
		(3 "B.Mask" user "Board Geometry/Soldermask Bottom")
		(17 "Dwgs.User" user "User.Drawings")
		(19 "Cmts.User" user "User.Comments")
		(21 "Eco1.User" user "User.Eco1")
		(23 "Eco2.User" user "User.Eco2")
		(25 "Edge.Cuts" user "Board Geometry/Outline")
		(27 "Margin" user)
		(31 "F.CrtYd" user "Package Geometry/Place Bound Top")
		(29 "B.CrtYd" user "Package Geometry/Place Bound Bottom")
		(35 "F.Fab" user "Ref Des/Assembly Top")
		(33 "B.Fab" user "Ref Des/Assembly Bottom")
	)
	(footprint ""
		(layer "F.Cu")
		(at 221.359984 -175.618394)
		(property "Reference" "Q18"
			(at 0 0 0)
			(layer "F.SilkS")
			(hide yes)
			(effects
				(font
					(size 1.27 1.27)
				)
			)
		)
		(property "Value" "2N7002DW-7F-GP"
			(at -2.3622 -8.2042 0)
			(unlocked yes)
			(layer "F.Fab")
			(hide yes)
			(effects
				(font
					(size 1.016 1.016)
					(thickness 0.1524)
				)
			)
		)
		(property "Device Type" "SOT-363H44"
			(at -2.3622 -10.1092 0)
			(unlocked yes)
			(layer "F.Fab")
			(hide yes)
			(effects
				(font
					(size 1.016 1.016)
					(thickness 0.1524)
				)
			)
		)
		(duplicate_pad_numbers_are_jumpers no)
		(fp_line
			(start -1.4478 -1.7018)
			(end -1.4478 1.7018)
			(stroke
				(width 0.1524)
				(type default)
			)
			(layer "F.SilkS")
		)
		(fp_line
			(start -1.4478 1.7018)
			(end 1.4478 1.7018)
			(stroke
				(width 0.1524)
				(type default)
			)
			(layer "F.SilkS")
		)
		(fp_line
			(start -1.27 1.524)
			(end -1.27 0.6604)
			(stroke
				(width 0.4826)
				(type default)
			)
			(layer "F.SilkS")
		)
		(fp_line
			(start 1.4478 -1.7018)
			(end -1.4478 -1.7018)
			(stroke
				(width 0.1524)
				(type default)
			)
			(layer "F.SilkS")
		)
		(fp_line
			(start 1.4478 1.7018)
			(end 1.4478 -1.7018)
			(stroke
				(width 0.1524)
				(type default)
			)
			(layer "F.SilkS")
		)
		(fp_poly
			(pts
				(xy -1.524 -1.778) (xy 1.524 -1.778) (xy 1.524 1.778) (xy -1.524 1.778)
			)
			(stroke
				(width 0)
				(type default)
			)
			(fill no)
			(layer "F.CrtYd")
		)
		(fp_poly
			(pts
				(xy -1.524 -1.778) (xy 1.524 -1.778) (xy 1.524 1.778) (xy -1.524 1.778)
			)
			(stroke
				(width 0)
				(type default)
			)
			(fill no)
			(layer "F.Fab")
		)
		(pad "1" smd rect
			(at -0.65024 0.9398)
			(size 0.4064 1.016)
			(layers "F.Cu" "F.Mask" "F.Paste")
			(net "GND")
		)
		(pad "2" smd rect
			(at 0 0.9398)
			(size 0.4064 1.016)
			(layers "F.Cu" "F.Mask" "F.Paste")
			(net "INVERTER_G2_EXP")
		)
		(pad "3" smd rect
			(at 0.65024 0.9398)
			(size 0.4064 1.016)
			(layers "F.Cu" "F.Mask" "F.Paste")
			(net "INVERTER_G2_EXP")
		)
		(pad "4" smd rect
			(at 0.65024 -0.9398)
			(size 0.4064 1.016)
			(layers "F.Cu" "F.Mask" "F.Paste")
			(net "GND")
		)
		(pad "5" smd rect
			(at 0 -0.9398)
			(size 0.4064 1.016)
			(layers "F.Cu" "F.Mask" "F.Paste")
			(net "INVERTER_G1_EXP")
		)
		(pad "6" smd rect
			(at -0.65024 -0.9398)
			(size 0.4064 1.016)
			(layers "F.Cu" "F.Mask" "F.Paste")
			(net "HB_EXP_TO_BMC")
		)
	)
	(footprint ""
		(layer "F.Cu")
		(at 337.185 -110.49 180)
		(property "Reference" "PC20"
			(at 0 0 180)
			(layer "F.SilkS")
			(hide yes)
			(effects
				(font
					(size 1.27 1.27)
				)
			)
		)
		(property "Value" "SC1U10V2KX-1GP"
			(at 1.1811 -2.7051 180)
			(unlocked yes)
			(layer "F.Fab")
			(hide yes)
			(effects
				(font
					(size 1.016 1.016)
					(thickness 0.1524)
				)
			)
		)
		(property "Device Type" "C402H22"
			(at 1.1811 -4.2291 180)
			(unlocked yes)
			(layer "F.Fab")
			(hide yes)
			(effects
				(font
					(size 1.016 1.016)
					(thickness 0.1524)
				)
			)
		)
		(duplicate_pad_numbers_are_jumpers no)
		(fp_rect
			(start -0.4318 0.9525)
			(end 0.4318 -0.9525)
			(stroke
				(width 0)
				(type default)
			)
			(fill no)
			(layer "F.CrtYd")
		)
		(fp_rect
			(start -0.4318 0.9525)
			(end 0.4318 -0.9525)
			(stroke
				(width 0)
				(type default)
			)
			(fill no)
			(layer "F.Fab")
		)
		(pad "1" smd custom
			(at 0 -0.4445 180)
			(size 0.1524 0.1524)
			(layers "F.Cu" "F.Mask" "F.Paste")
			(net "GND")
			(options
				(clearance outline)
				(anchor circle)
			)
			(primitives
				(gr_poly
					(pts
						(arc
							(start 0.3048 -0.2032)
							(mid 0.275042 -0.275042)
							(end 0.2032 -0.3048)
						)
						(arc
							(start -0.2032 -0.3048)
							(mid -0.275042 -0.275042)
							(end -0.3048 -0.2032)
						)
						(arc
							(start -0.3048 0.2032)
							(mid -0.275042 0.275042)
							(end -0.2032 0.3048)
						)
						(arc
							(start 0.2032 0.3048)
							(mid 0.275042 0.275042)
							(end 0.3048 0.2032)
						)
					)
					(width 0)
					(fill yes)
				)
			)
		)
		(pad "2" smd custom
			(at 0 0.4445 180)
			(size 0.1524 0.1524)
			(layers "F.Cu" "F.Mask" "F.Paste")
			(net "P5V_STBY_EN_R")
			(options
				(clearance outline)
				(anchor circle)
			)
			(primitives
				(gr_poly
					(pts
						(arc
							(start 0.3048 -0.2032)
							(mid 0.275042 -0.275042)
							(end 0.2032 -0.3048)
						)
						(arc
							(start -0.2032 -0.3048)
							(mid -0.275042 -0.275042)
							(end -0.3048 -0.2032)
						)
						(arc
							(start -0.3048 0.2032)
							(mid -0.275042 0.275042)
							(end -0.2032 0.3048)
						)
						(arc
							(start 0.2032 0.3048)
							(mid 0.275042 0.275042)
							(end 0.3048 0.2032)
						)
					)
					(width 0)
					(fill yes)
				)
			)
		)
	)
	(footprint ""
		(layer "F.Cu")
		(at 308.737 -112.776 -90)
		(property "Reference" "PR21"
			(at 0 0 270)
			(layer "F.SilkS")
			(hide yes)
			(effects
				(font
					(size 1.27 1.27)
				)
			)
		)
		(property "Value" "0R2J-2-GP"
			(at 0.064008 -3.993896 270)
			(unlocked yes)
			(layer "F.Fab")
			(hide yes)
			(effects
				(font
					(size 1.016 1.016)
					(thickness 0.1524)
				)
			)
		)
		(property "Device Type" "R402H16"
			(at 0.064008 -5.517896 270)
			(unlocked yes)
			(layer "F.Fab")
			(hide yes)
			(effects
				(font
					(size 1.016 1.016)
					(thickness 0.1524)
				)
			)
		)
		(duplicate_pad_numbers_are_jumpers no)
		(fp_line
			(start -0.508 -0.9398)
			(end -0.508 0.9398)
			(stroke
				(width 0.1524)
				(type default)
			)
			(layer "F.SilkS")
		)
		(fp_line
			(start 0.508 -0.9398)
			(end -0.508 -0.9398)
			(stroke
				(width 0.1524)
				(type default)
			)
			(layer "F.SilkS")
		)
		(fp_rect
			(start -0.508 0.9398)
			(end 0.508 -0.9398)
			(stroke
				(width 0)
				(type default)
			)
			(fill no)
			(layer "F.CrtYd")
		)
		(fp_rect
			(start -0.508 0.9398)
			(end 0.508 -0.9398)
			(stroke
				(width 0)
				(type default)
			)
			(fill no)
			(layer "F.Fab")
		)
		(pad "1" smd custom
			(at 0 -0.4445 270)
			(size 0.1397 0.1397)
			(layers "F.Cu" "F.Mask" "F.Paste")
			(net "P3V3_STBY_EN")
			(options
				(clearance outline)
				(anchor circle)
			)
			(primitives
				(gr_poly
					(pts
						(arc
							(start -0.1778 -0.2794)
							(mid -0.249642 -0.249642)
							(end -0.2794 -0.1778)
						)
						(arc
							(start -0.2794 0.1778)
							(mid -0.249642 0.249642)
							(end -0.1778 0.2794)
						)
						(arc
							(start 0.1778 0.2794)
							(mid 0.249642 0.249642)
							(end 0.2794 0.1778)
						)
						(arc
							(start 0.2794 -0.1778)
							(mid 0.249642 -0.249642)
							(end 0.1778 -0.2794)
						)
					)
					(width 0)
					(fill yes)
				)
			)
		)
		(pad "2" smd custom
			(at 0 0.4445 270)
			(size 0.1397 0.1397)
			(layers "F.Cu" "F.Mask" "F.Paste")
			(net "P5V_STBY_PG")
			(options
				(clearance outline)
				(anchor circle)
			)
			(primitives
				(gr_poly
					(pts
						(arc
							(start -0.1778 -0.2794)
							(mid -0.249642 -0.249642)
							(end -0.2794 -0.1778)
						)
						(arc
							(start -0.2794 0.1778)
							(mid -0.249642 0.249642)
							(end -0.1778 0.2794)
						)
						(arc
							(start 0.1778 0.2794)
							(mid 0.249642 0.249642)
							(end 0.2794 0.1778)
						)
						(arc
							(start 0.2794 -0.1778)
							(mid 0.249642 -0.249642)
							(end 0.1778 -0.2794)
						)
					)
					(width 0)
					(fill yes)
				)
			)
		)
	)
	(footprint ""
		(layer "F.Cu")
		(at 47.9552 -120.5992 90)
		(property "Reference" "SR940"
			(at 0 0 90)
			(layer "F.SilkS")
			(hide yes)
			(effects
				(font
					(size 1.27 1.27)
				)
			)
		)
		(property "Value" "0R2J-2-GP"
			(at 0.064008 -3.993896 90)
			(unlocked yes)
			(layer "F.Fab")
			(hide yes)
			(effects
				(font
					(size 1.016 1.016)
					(thickness 0.1524)
				)
			)
		)
		(property "Device Type" "R402H16"
			(at 0.064008 -5.517896 90)
			(unlocked yes)
			(layer "F.Fab")
			(hide yes)
			(effects
				(font
					(size 1.016 1.016)
					(thickness 0.1524)
				)
			)
		)
		(duplicate_pad_numbers_are_jumpers no)
		(fp_line
			(start 0.508 -0.9398)
			(end -0.508 -0.9398)
			(stroke
				(width 0.1524)
				(type default)
			)
			(layer "F.SilkS")
		)
		(fp_line
			(start -0.508 -0.9398)
			(end -0.508 0.9398)
			(stroke
				(width 0.1524)
				(type default)
			)
			(layer "F.SilkS")
		)
		(fp_rect
			(start -0.508 0.9398)
			(end 0.508 -0.9398)
			(stroke
				(width 0)
				(type default)
			)
			(fill no)
			(layer "F.CrtYd")
		)
		(fp_rect
			(start -0.508 0.9398)
			(end 0.508 -0.9398)
			(stroke
				(width 0)
				(type default)
			)
			(fill no)
			(layer "F.Fab")
		)
		(pad "1" smd custom
			(at 0 -0.4445 90)
			(size 0.1397 0.1397)
			(layers "F.Cu" "F.Mask" "F.Paste")
			(net "SDB_RX_R")
			(options
				(clearance outline)
				(anchor circle)
			)
			(primitives
				(gr_poly
					(pts
						(arc
							(start -0.1778 -0.2794)
							(mid -0.249642 -0.249642)
							(end -0.2794 -0.1778)
						)
						(arc
							(start -0.2794 0.1778)
							(mid -0.249642 0.249642)
							(end -0.1778 0.2794)
						)
						(arc
							(start 0.1778 0.2794)
							(mid 0.249642 0.249642)
							(end 0.2794 0.1778)
						)
						(arc
							(start 0.2794 -0.1778)
							(mid 0.249642 -0.249642)
							(end 0.1778 -0.2794)
						)
					)
					(width 0)
					(fill yes)
				)
			)
		)
		(pad "2" smd custom
			(at 0 0.4445 90)
			(size 0.1397 0.1397)
			(layers "F.Cu" "F.Mask" "F.Paste")
			(net "SDB_RX")
			(options
				(clearance outline)
				(anchor circle)
			)
			(primitives
				(gr_poly
					(pts
						(arc
							(start -0.1778 -0.2794)
							(mid -0.249642 -0.249642)
							(end -0.2794 -0.1778)
						)
						(arc
							(start -0.2794 0.1778)
							(mid -0.249642 0.249642)
							(end -0.1778 0.2794)
						)
						(arc
							(start 0.1778 0.2794)
							(mid 0.249642 0.249642)
							(end 0.2794 0.1778)
						)
						(arc
							(start 0.2794 -0.1778)
							(mid 0.249642 -0.249642)
							(end 0.1778 -0.2794)
						)
					)
					(width 0)
					(fill yes)
				)
			)
		)
	)
	(footprint ""
		(layer "F.Cu")
		(at 321.31 -149.987 90)
		(property "Reference" "U43"
			(at 0 0 90)
			(layer "F.SilkS")
			(hide yes)
			(effects
				(font
					(size 1.27 1.27)
				)
			)
		)
		(property "Value" "PCF8563T-1-GP"
			(at -3.707384 -1.5367 90)
			(unlocked yes)
			(layer "F.Fab")
			(hide yes)
			(effects
				(font
					(size 1.016 1.016)
					(thickness 0.1524)
				)
			)
		)
		(property "Device Type" "SOIC8H69"
			(at -3.707384 -3.0607 90)
			(unlocked yes)
			(layer "F.Fab")
			(hide yes)
			(effects
				(font
					(size 1.016 1.016)
					(thickness 0.1524)
				)
			)
		)
		(duplicate_pad_numbers_are_jumpers no)
		(fp_line
			(start 2.1336 -1.4224)
			(end -2.7432 -1.4224)
			(stroke
				(width 0.1524)
				(type default)
			)
			(layer "F.SilkS")
		)
		(fp_line
			(start -2.7432 -1.4224)
			(end -2.7432 1.4224)
			(stroke
				(width 0.1524)
				(type default)
			)
			(layer "F.SilkS")
		)
		(fp_line
			(start -2.7178 -0.508)
			(end -2.1844 -0.0508)
			(stroke
				(width 0.1524)
				(type default)
			)
			(layer "F.SilkS")
		)
		(fp_line
			(start -2.1844 -0.0508)
			(end -2.7178 0.508)
			(stroke
				(width 0.1524)
				(type default)
			)
			(layer "F.SilkS")
		)
		(fp_line
			(start 2.1336 1.4224)
			(end 2.1336 -1.4224)
			(stroke
				(width 0.1524)
				(type default)
			)
			(layer "F.SilkS")
		)
		(fp_line
			(start -2.7432 1.4224)
			(end 2.1336 1.4224)
			(stroke
				(width 0.1524)
				(type default)
			)
			(layer "F.SilkS")
		)
		(fp_line
			(start -2.7432 1.4224)
			(end -2.6416 1.4224)
			(stroke
				(width 0.1524)
				(type default)
			)
			(layer "F.SilkS")
		)
		(fp_line
			(start -2.6289 3.4417)
			(end -2.6289 1.4732)
			(stroke
				(width 0.381)
				(type default)
			)
			(layer "F.SilkS")
		)
		(fp_poly
			(pts
				(xy -2.2098 -1.4224) (xy -2.2098 1.4224) (xy 2.2098 1.4224) (xy 2.2098 -1.4224)
			)
			(stroke
				(width 0)
				(type default)
			)
			(fill yes)
			(layer "F.SilkS")
		)
		(fp_rect
			(start -2.450084 2.999994)
			(end 2.450084 -2.999994)
			(stroke
				(width 0)
				(type default)
			)
			(fill no)
			(layer "F.CrtYd")
		)
		(fp_poly
			(pts
				(xy -2.8194 3.6322) (xy -2.8194 -3.6322) (xy 2.8194 -3.6322) (xy 2.8194 1.18364) (xy 2.450084 1.18364)
				(xy 2.450084 -2.999994) (xy -2.450084 -2.999994) (xy -2.450084 2.999994) (xy 2.450084 2.999994)
				(xy 2.450084 1.18618) (xy 2.8194 1.18618) (xy 2.8194 3.6322)
			)
			(stroke
				(width 0)
				(type default)
			)
			(fill no)
			(layer "F.CrtYd")
		)
		(fp_rect
			(start -2.8194 3.6322)
			(end 2.8194 -3.6322)
			(stroke
				(width 0)
				(type default)
			)
			(fill no)
			(layer "F.Fab")
		)
		(pad "1" smd rect
			(at -1.905 2.54 90)
			(size 0.635 1.651)
			(layers "F.Cu" "F.Mask" "F.Paste")
			(net "RTC_OSCI")
		)
		(pad "2" smd rect
			(at -0.635 2.54 90)
			(size 0.635 1.651)
			(layers "F.Cu" "F.Mask" "F.Paste")
			(net "RTC_OSCO")
		)
		(pad "3" smd rect
			(at 0.635 2.54 90)
			(size 0.635 1.651)
			(layers "F.Cu" "F.Mask" "F.Paste")
			(net "RTC_INT_N")
		)
		(pad "4" smd rect
			(at 1.905 2.54 90)
			(size 0.635 1.651)
			(layers "F.Cu" "F.Mask" "F.Paste")
			(net "GND")
		)
		(pad "5" smd rect
			(at 1.905 -2.54 90)
			(size 0.635 1.651)
			(layers "F.Cu" "F.Mask" "F.Paste")
			(net "RTC_I2C_SDA")
		)
		(pad "6" smd rect
			(at 0.635 -2.54 90)
			(size 0.635 1.651)
			(layers "F.Cu" "F.Mask" "F.Paste")
			(net "RTC_I2C_SCL")
		)
		(pad "7" smd rect
			(at -0.635 -2.54 90)
			(size 0.635 1.651)
			(layers "F.Cu" "F.Mask" "F.Paste")
			(net "RTC_CLK_OUT")
		)
		(pad "8" smd rect
			(at -1.905 -2.54 90)
			(size 0.635 1.651)
			(layers "F.Cu" "F.Mask" "F.Paste")
			(net "P3V3_RTC")
		)
	)
	(footprint ""
		(layer "F.Cu")
		(at 291.973 -206.756 90)
		(property "Reference" "C174"
			(at 0 0 90)
			(layer "F.SilkS")
			(hide yes)
			(effects
				(font
					(size 1.27 1.27)
				)
			)
		)
		(property "Value" "SCD1U16V2KX-3GP"
			(at 1.1811 -2.7051 90)
			(unlocked yes)
			(layer "F.Fab")
			(hide yes)
			(effects
				(font
					(size 1.016 1.016)
					(thickness 0.1524)
				)
			)
		)
		(property "Device Type" "C402H22"
			(at 1.1811 -4.2291 90)
			(unlocked yes)
			(layer "F.Fab")
			(hide yes)
			(effects
				(font
					(size 1.016 1.016)
					(thickness 0.1524)
				)
			)
		)
		(duplicate_pad_numbers_are_jumpers no)
		(fp_rect
			(start -0.4318 0.9525)
			(end 0.4318 -0.9525)
			(stroke
				(width 0)
				(type default)
			)
			(fill no)
			(layer "F.CrtYd")
		)
		(fp_rect
			(start -0.4318 0.9525)
			(end 0.4318 -0.9525)
			(stroke
				(width 0)
				(type default)
			)
			(fill no)
			(layer "F.Fab")
		)
		(pad "1" smd custom
			(at 0 -0.4445 90)
			(size 0.1524 0.1524)
			(layers "F.Cu" "F.Mask" "F.Paste")
			(net "DDR_VREF")
			(options
				(clearance outline)
				(anchor circle)
			)
			(primitives
				(gr_poly
					(pts
						(arc
							(start 0.3048 -0.2032)
							(mid 0.275042 -0.275042)
							(end 0.2032 -0.3048)
						)
						(arc
							(start -0.2032 -0.3048)
							(mid -0.275042 -0.275042)
							(end -0.3048 -0.2032)
						)
						(arc
							(start -0.3048 0.2032)
							(mid -0.275042 0.275042)
							(end -0.2032 0.3048)
						)
						(arc
							(start 0.2032 0.3048)
							(mid 0.275042 0.275042)
							(end 0.3048 0.2032)
						)
					)
					(width 0)
					(fill yes)
				)
			)
		)
		(pad "2" smd custom
			(at 0 0.4445 90)
			(size 0.1524 0.1524)
			(layers "F.Cu" "F.Mask" "F.Paste")
			(net "GND")
			(options
				(clearance outline)
				(anchor circle)
			)
			(primitives
				(gr_poly
					(pts
						(arc
							(start 0.3048 -0.2032)
							(mid 0.275042 -0.275042)
							(end 0.2032 -0.3048)
						)
						(arc
							(start -0.2032 -0.3048)
							(mid -0.275042 -0.275042)
							(end -0.3048 -0.2032)
						)
						(arc
							(start -0.3048 0.2032)
							(mid -0.275042 0.275042)
							(end -0.2032 0.3048)
						)
						(arc
							(start 0.2032 0.3048)
							(mid 0.275042 0.275042)
							(end 0.3048 0.2032)
						)
					)
					(width 0)
					(fill yes)
				)
			)
		)
	)
	(footprint ""
		(layer "F.Cu")
		(at 312.547 -191.262 90)
		(property "Reference" "R804"
			(at 0 0 90)
			(layer "F.SilkS")
			(hide yes)
			(effects
				(font
					(size 1.27 1.27)
				)
			)
		)
		(property "Value" "4K7R2F-GP"
			(at 0.064008 -3.993896 90)
			(unlocked yes)
			(layer "F.Fab")
			(hide yes)
			(effects
				(font
					(size 1.016 1.016)
					(thickness 0.1524)
				)
			)
		)
		(property "Device Type" "R402H16"
			(at 0.064008 -5.517896 90)
			(unlocked yes)
			(layer "F.Fab")
			(hide yes)
			(effects
				(font
					(size 1.016 1.016)
					(thickness 0.1524)
				)
			)
		)
		(duplicate_pad_numbers_are_jumpers no)
		(fp_line
			(start 0.508 -0.9398)
			(end -0.508 -0.9398)
			(stroke
				(width 0.1524)
				(type default)
			)
			(layer "F.SilkS")
		)
		(fp_line
			(start -0.508 -0.9398)
			(end -0.508 0.9398)
			(stroke
				(width 0.1524)
				(type default)
			)
			(layer "F.SilkS")
		)
		(fp_rect
			(start -0.508 0.9398)
			(end 0.508 -0.9398)
			(stroke
				(width 0)
				(type default)
			)
			(fill no)
			(layer "F.CrtYd")
		)
		(fp_rect
			(start -0.508 0.9398)
			(end 0.508 -0.9398)
			(stroke
				(width 0)
				(type default)
			)
			(fill no)
			(layer "F.Fab")
		)
		(pad "1" smd custom
			(at 0 -0.4445 90)
			(size 0.1397 0.1397)
			(layers "F.Cu" "F.Mask" "F.Paste")
			(net "P3V3_STBY")
			(options
				(clearance outline)
				(anchor circle)
			)
			(primitives
				(gr_poly
					(pts
						(arc
							(start -0.1778 -0.2794)
							(mid -0.249642 -0.249642)
							(end -0.2794 -0.1778)
						)
						(arc
							(start -0.2794 0.1778)
							(mid -0.249642 0.249642)
							(end -0.1778 0.2794)
						)
						(arc
							(start 0.1778 0.2794)
							(mid 0.249642 0.249642)
							(end 0.2794 0.1778)
						)
						(arc
							(start 0.2794 -0.1778)
							(mid 0.249642 -0.249642)
							(end 0.1778 -0.2794)
						)
					)
					(width 0)
					(fill yes)
				)
			)
		)
		(pad "2" smd custom
			(at 0 0.4445 90)
			(size 0.1397 0.1397)
			(layers "F.Cu" "F.Mask" "F.Paste")
			(net "JTAG_BMC_TCK")
			(options
				(clearance outline)
				(anchor circle)
			)
			(primitives
				(gr_poly
					(pts
						(arc
							(start -0.1778 -0.2794)
							(mid -0.249642 -0.249642)
							(end -0.2794 -0.1778)
						)
						(arc
							(start -0.2794 0.1778)
							(mid -0.249642 0.249642)
							(end -0.1778 0.2794)
						)
						(arc
							(start 0.1778 0.2794)
							(mid 0.249642 0.249642)
							(end 0.2794 0.1778)
						)
						(arc
							(start 0.2794 -0.1778)
							(mid 0.249642 -0.249642)
							(end 0.1778 -0.2794)
						)
					)
					(width 0)
					(fill yes)
				)
			)
		)
	)
)
